(kicad_pcb
	(version 20260206)
	(generator "pcbnew")
	(generator_version "10.0")
	(general
		(thickness 1.6)
		(legacy_teardrops no)
	)
	(paper "A4")
	(title_block
		(title "v2-pdb — ms_pdb_v2.brd")
		(comment 1 "Open CloudServer (Microsoft) / footprints 96-102 of 348")
	)
	(layers
		(0 "F.Cu" signal "TOP")
		(4 "In1.Cu" signal "GND")
		(6 "In2.Cu" signal "IN1")
		(8 "In3.Cu" signal "VCC")
		(10 "In4.Cu" signal "VCC1")
		(12 "In5.Cu" signal "IN2")
		(14 "In6.Cu" signal "GND1")
		(2 "B.Cu" signal "BOTTOM")
		(9 "F.Adhes" user "F.Adhesive")
		(11 "B.Adhes" user "B.Adhesive")
		(13 "F.Paste" user "Package Geometry/Pastemask Top")
		(15 "B.Paste" user "Package Geometry/Pastemask Bottom")
		(5 "F.SilkS" user "Ref Des/Silkscreen Top")
		(7 "B.SilkS" user "Ref Des/Silkscreen Bottom")
		(1 "F.Mask" user "Board Geometry/Soldermask Top")
		(3 "B.Mask" user "Board Geometry/Soldermask Bottom")
		(17 "Dwgs.User" user "User.Drawings")
		(19 "Cmts.User" user "User.Comments")
		(21 "Eco1.User" user "User.Eco1")
		(23 "Eco2.User" user "User.Eco2")
		(25 "Edge.Cuts" user "Board Geometry/Outline")
		(27 "Margin" user)
		(31 "F.CrtYd" user "Package Geometry/Place Bound Top")
		(29 "B.CrtYd" user "Package Geometry/Place Bound Bottom")
		(35 "F.Fab" user "Ref Des/Assembly Top")
		(33 "B.Fab" user "Ref Des/Assembly Bottom")
	)
	(footprint ""
		(layer "F.Cu")
		(at 50.743612 -151.92502 180)
		(property "Reference" "CE8"
			(at -4.261612 -1.5494 0)
			(unlocked yes)
			(layer "F.SilkS")
			(effects
				(font
					(size 0.7874 0.5842)
					(thickness 0.1524)
				)
				(justify left)
			)
		)
		(property "Value" ""
			(at 0 0 180)
			(layer "F.Fab")
			(effects
				(font
					(size 1.27 1.27)
				)
			)
		)
		(duplicate_pad_numbers_are_jumpers no)
		(fp_line
			(start 0 -4.2672)
			(end 0 4.2672)
			(stroke
				(width 0.1524)
				(type default)
			)
			(layer "F.SilkS")
		)
		(fp_circle
			(center 0 0)
			(end -4.2672 0)
			(stroke
				(width 0.1524)
				(type default)
			)
			(fill no)
			(layer "F.SilkS")
		)
		(fp_poly
			(pts
				(arc
					(start 0 -4.2672)
					(mid 4.2672 0)
					(end 0 4.2672)
				)
			)
			(stroke
				(width 0)
				(type default)
			)
			(fill yes)
			(layer "F.SilkS")
		)
		(fp_poly
			(pts
				(xy -2.5146 -0.762) (xy -0.9906 -0.762) (xy -0.9906 0.762) (xy -2.5146 0.762)
			)
			(stroke
				(width 0)
				(type default)
			)
			(fill no)
			(layer "B.CrtYd")
		)
		(fp_poly
			(pts
				(arc
					(start 1.7526 0.762)
					(mid 2.291415 -0.538815)
					(end 0.9906 0)
				)
				(arc
					(start 0.9906 0.0254)
					(mid 1.206345 0.546255)
					(end 1.7272 0.762)
				)
			)
			(stroke
				(width 0)
				(type default)
			)
			(fill no)
			(layer "B.CrtYd")
		)
		(fp_poly
			(pts
				(arc
					(start -4.2672 0)
					(mid 4.2672 0)
					(end -4.2672 0)
				)
			)
			(stroke
				(width 0)
				(type default)
			)
			(fill no)
			(layer "F.CrtYd")
		)
		(fp_circle
			(center 0 0)
			(end -4.2672 0)
			(stroke
				(width 0.1)
				(type default)
			)
			(fill no)
			(layer "F.Fab")
		)
		(fp_text user "+"
			(at -4.996688 -3.352292 180)
			(unlocked yes)
			(layer "F.SilkS")
			(effects
				(font
					(size 1.905 1.4224)
					(thickness 0.1524)
				)
				(justify left)
			)
		)
		(fp_text user "+"
			(at -5.6642 -0.34925 180)
			(unlocked yes)
			(layer "F.Fab")
			(effects
				(font
					(size 1.905 1.4224)
					(thickness 0.000001)
				)
				(justify left)
			)
		)
		(pad "1" thru_hole rect
			(at -1.75006 0 180)
			(size 1.397 1.397)
			(drill 0.9144)
			(layers "*.Cu" "*.Mask")
			(remove_unused_layers no)
			(net "P12V")
			(clearance 0.0127)
			(thermal_gap 0.0127)
			(padstack
				(mode front_inner_back)
				(layer "Inner"
					(shape circle)
					(size 1.397 1.397)
					(clearance 0.0127)
				)
				(layer "B.Cu"
					(shape rect)
					(size 1.397 1.397)
					(clearance 0.0127)
				)
			)
		)
		(pad "2" thru_hole circle
			(at 1.75006 0 180)
			(size 1.397 1.397)
			(drill 0.9144)
			(layers "*.Cu" "*.Mask")
			(remove_unused_layers no)
			(net "GND")
			(clearance 0.0127)
			(thermal_gap 0.0127)
		)
	)
	(footprint ""
		(layer "F.Cu")
		(at 75.059286 -152.923748 -90)
		(property "Reference" "C24"
			(at -2.638552 0.03937 90)
			(unlocked yes)
			(layer "F.SilkS")
			(effects
				(font
					(size 0.7874 0.5842)
					(thickness 0.1524)
				)
				(justify left)
			)
		)
		(property "Value" ""
			(at 0 0 270)
			(layer "F.Fab")
			(effects
				(font
					(size 1.27 1.27)
				)
			)
		)
		(duplicate_pad_numbers_are_jumpers no)
		(fp_line
			(start -0.7874 0.4064)
			(end -0.7874 -0.4064)
			(stroke
				(width 0.1524)
				(type default)
			)
			(layer "F.SilkS")
		)
		(fp_line
			(start 0.7874 0.4064)
			(end -0.7874 0.4064)
			(stroke
				(width 0.1524)
				(type default)
			)
			(layer "F.SilkS")
		)
		(fp_line
			(start 0 0.381)
			(end 0 -0.381)
			(stroke
				(width 0.1524)
				(type default)
			)
			(layer "F.SilkS")
		)
		(fp_line
			(start -0.7874 -0.4064)
			(end 0.7874 -0.4064)
			(stroke
				(width 0.1524)
				(type default)
			)
			(layer "F.SilkS")
		)
		(fp_line
			(start 0.7874 -0.4064)
			(end 0.7874 0.4064)
			(stroke
				(width 0.1524)
				(type default)
			)
			(layer "F.SilkS")
		)
		(fp_poly
			(pts
				(xy -0.5334 0.254) (xy -0.635 0.254) (xy -0.635 0.2286) (xy -0.635 -0.254) (xy -0.5334 -0.254) (xy -0.5334 -0.2794)
				(xy 0.5334 -0.2794) (xy 0.5334 -0.254) (xy 0.635 -0.254) (xy 0.635 0.254) (xy 0.5334 0.254) (xy 0.5334 0.2794)
				(xy -0.508 0.2794) (xy -0.5334 0.2794)
			)
			(stroke
				(width 0)
				(type default)
			)
			(fill no)
			(layer "F.CrtYd")
		)
		(pad "1" smd rect
			(at 0.40005 0 270)
			(size 0.4572 0.508)
			(layers "F.Cu" "F.Mask" "F.Paste")
			(net "P12V")
		)
		(pad "2" smd rect
			(at -0.40005 0 270)
			(size 0.4572 0.508)
			(layers "F.Cu" "F.Mask" "F.Paste")
			(net "GND")
		)
	)
	(footprint ""
		(layer "F.Cu")
		(at 50.554382 -418.636958 180)
		(property "Reference" "CE19"
			(at 6.458458 3.641344 0)
			(unlocked yes)
			(layer "F.SilkS")
			(effects
				(font
					(size 0.7874 0.5842)
					(thickness 0.1524)
				)
				(justify left)
			)
		)
		(property "Value" ""
			(at 0 0 180)
			(layer "F.Fab")
			(effects
				(font
					(size 1.27 1.27)
				)
			)
		)
		(duplicate_pad_numbers_are_jumpers no)
		(fp_line
			(start 0 -4.2672)
			(end 0 4.2672)
			(stroke
				(width 0.1524)
				(type default)
			)
			(layer "F.SilkS")
		)
		(fp_circle
			(center 0 0)
			(end -4.2672 0)
			(stroke
				(width 0.1524)
				(type default)
			)
			(fill no)
			(layer "F.SilkS")
		)
		(fp_poly
			(pts
				(arc
					(start 0 -4.2672)
					(mid 4.2672 0)
					(end 0 4.2672)
				)
			)
			(stroke
				(width 0)
				(type default)
			)
			(fill yes)
			(layer "F.SilkS")
		)
		(fp_poly
			(pts
				(xy -2.5146 -0.762) (xy -0.9906 -0.762) (xy -0.9906 0.762) (xy -2.5146 0.762)
			)
			(stroke
				(width 0)
				(type default)
			)
			(fill no)
			(layer "B.CrtYd")
		)
		(fp_poly
			(pts
				(arc
					(start 1.7526 0.762)
					(mid 2.291415 -0.538815)
					(end 0.9906 0)
				)
				(arc
					(start 0.9906 0.0254)
					(mid 1.206345 0.546255)
					(end 1.7272 0.762)
				)
			)
			(stroke
				(width 0)
				(type default)
			)
			(fill no)
			(layer "B.CrtYd")
		)
		(fp_poly
			(pts
				(arc
					(start -4.2672 0)
					(mid 4.2672 0)
					(end -4.2672 0)
				)
			)
			(stroke
				(width 0)
				(type default)
			)
			(fill no)
			(layer "F.CrtYd")
		)
		(fp_circle
			(center 0 0)
			(end -4.2672 0)
			(stroke
				(width 0.1)
				(type default)
			)
			(fill no)
			(layer "F.Fab")
		)
		(fp_text user "+"
			(at -5.740908 1.215136 180)
			(unlocked yes)
			(layer "F.SilkS")
			(effects
				(font
					(size 1.905 1.4224)
					(thickness 0.1524)
				)
				(justify left)
			)
		)
		(fp_text user "+"
			(at -5.6642 -0.34925 180)
			(unlocked yes)
			(layer "F.Fab")
			(effects
				(font
					(size 1.905 1.4224)
					(thickness 0.000001)
				)
				(justify left)
			)
		)
		(pad "1" thru_hole rect
			(at -1.75006 0 180)
			(size 1.397 1.397)
			(drill 0.9144)
			(layers "*.Cu" "*.Mask")
			(remove_unused_layers no)
			(net "P12V")
			(clearance 0.0127)
			(thermal_gap 0.0127)
			(padstack
				(mode front_inner_back)
				(layer "Inner"
					(shape circle)
					(size 1.397 1.397)
					(clearance 0.0127)
				)
				(layer "B.Cu"
					(shape rect)
					(size 1.397 1.397)
					(clearance 0.0127)
				)
			)
		)
		(pad "2" thru_hole circle
			(at 1.75006 0 180)
			(size 1.397 1.397)
			(drill 0.9144)
			(layers "*.Cu" "*.Mask")
			(remove_unused_layers no)
			(net "GND")
			(clearance 0.0127)
			(thermal_gap 0.0127)
		)
	)
	(footprint ""
		(layer "F.Cu")
		(at 16.599916 -206.99984)
		(property "Reference" "H2"
			(at -3.038856 -9.000998 0)
			(unlocked yes)
			(layer "F.SilkS")
			(effects
				(font
					(size 0.7874 0.5842)
					(thickness 0.1524)
				)
				(justify left)
			)
		)
		(property "Value" ""
			(at 0 0 0)
			(layer "F.Fab")
			(effects
				(font
					(size 1.27 1.27)
				)
			)
		)
		(duplicate_pad_numbers_are_jumpers no)
		(fp_circle
			(center 0 0)
			(end 7.999984 0)
			(stroke
				(width 0.1524)
				(type default)
			)
			(fill no)
			(layer "F.SilkS")
		)
		(fp_circle
			(center 0 0)
			(end 14.7066 0)
			(stroke
				(width 0.1524)
				(type default)
			)
			(fill no)
			(layer "B.SilkS")
		)
		(fp_poly
			(pts
				(arc
					(start 0 5.0038)
					(mid 0 -5.0038)
					(end 0 5.0038)
				)
			)
			(stroke
				(width 0)
				(type default)
			)
			(fill no)
			(layer "F.CrtYd")
		)
		(pad "" np_thru_hole circle
			(at 0 0)
			(size 4.0132 4.0132)
			(drill 4.0132)
			(layers "*.Cu" "*.Mask")
			(clearance 0.381)
			(thermal_gap 0.381)
		)
		(pad "2" thru_hole circle
			(at 0 -3.50012)
			(size 0.762 0.762)
			(drill 0.5588)
			(layers "*.Cu" "*.Mask")
			(remove_unused_layers no)
			(net "GND")
			(clearance 0.1524)
			(thermal_gap 0.1524)
		)
		(pad "3" thru_hole circle
			(at -2.500122 -2.500122)
			(size 0.762 0.762)
			(drill 0.5588)
			(layers "*.Cu" "*.Mask")
			(remove_unused_layers no)
			(net "GND")
			(clearance 0.1524)
			(thermal_gap 0.1524)
		)
		(pad "4" thru_hole circle
			(at -3.50012 0)
			(size 0.762 0.762)
			(drill 0.5588)
			(layers "*.Cu" "*.Mask")
			(remove_unused_layers no)
			(net "GND")
			(clearance 0.1524)
			(thermal_gap 0.1524)
		)
		(pad "5" thru_hole circle
			(at -2.500122 2.500122)
			(size 0.762 0.762)
			(drill 0.5588)
			(layers "*.Cu" "*.Mask")
			(remove_unused_layers no)
			(net "GND")
			(clearance 0.1524)
			(thermal_gap 0.1524)
		)
		(pad "6" thru_hole circle
			(at 0 3.50012)
			(size 0.762 0.762)
			(drill 0.5588)
			(layers "*.Cu" "*.Mask")
			(remove_unused_layers no)
			(net "GND")
			(clearance 0.1524)
			(thermal_gap 0.1524)
		)
		(pad "7" thru_hole circle
			(at 2.500122 2.500122)
			(size 0.762 0.762)
			(drill 0.5588)
			(layers "*.Cu" "*.Mask")
			(remove_unused_layers no)
			(net "GND")
			(clearance 0.1524)
			(thermal_gap 0.1524)
		)
		(pad "8" thru_hole circle
			(at 3.50012 0)
			(size 0.762 0.762)
			(drill 0.5588)
			(layers "*.Cu" "*.Mask")
			(remove_unused_layers no)
			(net "GND")
			(clearance 0.1524)
			(thermal_gap 0.1524)
		)
		(pad "9" thru_hole circle
			(at 2.500122 -2.500122)
			(size 0.762 0.762)
			(drill 0.5588)
			(layers "*.Cu" "*.Mask")
			(remove_unused_layers no)
			(net "GND")
			(clearance 0.1524)
			(thermal_gap 0.1524)
		)
		(zone
			(layer "F.Cu")
			(hatch none 0.5)
			(connect_pads
				(clearance 0)
			)
			(min_thickness 0.25)
			(keepout
				(tracks not_allowed)
				(vias allowed)
				(pads allowed)
				(copperpour not_allowed)
				(footprints allowed)
			)
			(placement
				(enabled no)
				(sheetname "")
			)
			(fill
				(thermal_gap 0.5)
				(thermal_bridge_width 0.5)
				(island_removal_mode 0)
			)
			(polygon
				(pts
					(arc
						(start 16.599916 -215.00084)
						(mid 8.598916 -206.99984)
						(end 16.599916 -198.99884)
					)
					(arc
						(start 16.599916 -198.99884)
						(mid 18.035016 -200.43394)
						(end 16.599916 -201.86904)
					)
					(arc
						(start 16.599916 -201.86904)
						(mid 11.469116 -206.99984)
						(end 16.599916 -212.13064)
					)
					(arc
						(start 16.599916 -212.13064)
						(mid 18.035016 -213.56574)
						(end 16.599916 -215.00084)
					)
				)
			)
		)
		(zone
			(layer "F.Cu")
			(hatch none 0.5)
			(connect_pads
				(clearance 0)
			)
			(min_thickness 0.25)
			(keepout
				(tracks not_allowed)
				(vias allowed)
				(pads allowed)
				(copperpour not_allowed)
				(footprints allowed)
			)
			(placement
				(enabled no)
				(sheetname "")
			)
			(fill
				(thermal_gap 0.5)
				(thermal_bridge_width 0.5)
				(island_removal_mode 0)
			)
			(polygon
				(pts
					(arc
						(start 16.599916 -215.00084)
						(mid 24.600916 -206.99984)
						(end 16.599916 -198.99884)
					)
					(arc
						(start 16.599916 -198.99884)
						(mid 15.164816 -200.43394)
						(end 16.599916 -201.86904)
					)
					(arc
						(start 16.599916 -201.86904)
						(mid 21.730716 -206.99984)
						(end 16.599916 -212.13064)
					)
					(arc
						(start 16.599916 -212.13064)
						(mid 15.164816 -213.56574)
						(end 16.599916 -215.00084)
					)
				)
			)
		)
		(zone
			(layers "F.Cu" "B.Cu" "In1.Cu" "In2.Cu" "In3.Cu" "In4.Cu" "In5.Cu" "In6.Cu")
			(hatch none 0.5)
			(connect_pads
				(clearance 0)
			)
			(min_thickness 0.25)
			(keepout
				(tracks not_allowed)
				(vias allowed)
				(pads allowed)
				(copperpour not_allowed)
				(footprints allowed)
			)
			(placement
				(enabled no)
				(sheetname "")
			)
			(fill
				(thermal_gap 0.5)
				(thermal_bridge_width 0.5)
				(island_removal_mode 0)
			)
			(polygon
				(pts
					(arc
						(start 16.599916 -204.48778)
						(mid 16.599916 -209.5119)
						(end 16.599916 -204.48778)
					)
				)
			)
		)
	)
	(footprint ""
		(layer "F.Cu")
		(at 71.392796 -83.335368 90)
		(property "Reference" "C21"
			(at 1.101852 -0.164846 90)
			(unlocked yes)
			(layer "F.SilkS")
			(effects
				(font
					(size 0.7874 0.5842)
					(thickness 0.1524)
				)
				(justify left)
			)
		)
		(property "Value" ""
			(at 0 0 90)
			(layer "F.Fab")
			(effects
				(font
					(size 1.27 1.27)
				)
			)
		)
		(duplicate_pad_numbers_are_jumpers no)
		(fp_line
			(start 0.7874 -0.4064)
			(end 0.7874 0.4064)
			(stroke
				(width 0.1524)
				(type default)
			)
			(layer "F.SilkS")
		)
		(fp_line
			(start -0.7874 -0.4064)
			(end 0.7874 -0.4064)
			(stroke
				(width 0.1524)
				(type default)
			)
			(layer "F.SilkS")
		)
		(fp_line
			(start 0 0.381)
			(end 0 -0.381)
			(stroke
				(width 0.1524)
				(type default)
			)
			(layer "F.SilkS")
		)
		(fp_line
			(start 0.7874 0.4064)
			(end -0.7874 0.4064)
			(stroke
				(width 0.1524)
				(type default)
			)
			(layer "F.SilkS")
		)
		(fp_line
			(start -0.7874 0.4064)
			(end -0.7874 -0.4064)
			(stroke
				(width 0.1524)
				(type default)
			)
			(layer "F.SilkS")
		)
		(fp_poly
			(pts
				(xy -0.5334 0.254) (xy -0.635 0.254) (xy -0.635 0.2286) (xy -0.635 -0.254) (xy -0.5334 -0.254) (xy -0.5334 -0.2794)
				(xy 0.5334 -0.2794) (xy 0.5334 -0.254) (xy 0.635 -0.254) (xy 0.635 0.254) (xy 0.5334 0.254) (xy 0.5334 0.2794)
				(xy -0.508 0.2794) (xy -0.5334 0.2794)
			)
			(stroke
				(width 0)
				(type default)
			)
			(fill no)
			(layer "F.CrtYd")
		)
		(pad "1" smd rect
			(at 0.40005 0 90)
			(size 0.4572 0.508)
			(layers "F.Cu" "F.Mask" "F.Paste")
			(net "P12V")
		)
		(pad "2" smd rect
			(at -0.40005 0 90)
			(size 0.4572 0.508)
			(layers "F.Cu" "F.Mask" "F.Paste")
			(net "GND")
		)
	)
	(footprint ""
		(layer "F.Cu")
		(at 46.436788 -251.703332 180)
		(property "Reference" "R100"
			(at 2.469388 -1.292098 0)
			(unlocked yes)
			(layer "F.SilkS")
			(effects
				(font
					(size 0.7874 0.5842)
					(thickness 0.1524)
				)
				(justify left)
			)
		)
		(property "Value" ""
			(at 0 0 180)
			(layer "F.Fab")
			(effects
				(font
					(size 1.27 1.27)
				)
			)
		)
		(duplicate_pad_numbers_are_jumpers no)
		(fp_line
			(start 0.7874 0.4064)
			(end -0.7874 0.4064)
			(stroke
				(width 0.1524)
				(type default)
			)
			(layer "F.SilkS")
		)
		(fp_line
			(start 0.7874 -0.4064)
			(end 0.7874 0.4064)
			(stroke
				(width 0.1524)
				(type default)
			)
			(layer "F.SilkS")
		)
		(fp_line
			(start -0.7874 0.4064)
			(end -0.7874 -0.4064)
			(stroke
				(width 0.1524)
				(type default)
			)
			(layer "F.SilkS")
		)
		(fp_line
			(start -0.7874 -0.4064)
			(end 0.7874 -0.4064)
			(stroke
				(width 0.1524)
				(type default)
			)
			(layer "F.SilkS")
		)
		(fp_poly
			(pts
				(xy -0.508 0.2794) (xy -0.508 0.2286) (xy -0.635 0.2286) (xy -0.635 -0.254) (xy -0.5334 -0.254)
				(xy -0.5334 -0.2794) (xy 0.5334 -0.2794) (xy 0.5334 -0.254) (xy 0.635 -0.254) (xy 0.635 0.254) (xy 0.5334 0.254)
				(xy 0.5334 0.2794)
			)
			(stroke
				(width 0)
				(type default)
			)
			(fill no)
			(layer "F.CrtYd")
		)
		(pad "1" smd rect
			(at 0.40005 0 180)
			(size 0.4572 0.508)
			(layers "F.Cu" "F.Mask" "F.Paste")
			(net "PSU6_REMOTE_R_P")
		)
		(pad "2" smd rect
			(at -0.40005 0 180)
			(size 0.4572 0.508)
			(layers "F.Cu" "F.Mask" "F.Paste")
			(net "P12V")
		)
	)
	(footprint ""
		(layer "F.Cu")
		(at 26.492708 -14.7955)
		(property "Reference" "R134"
			(at -3.978148 -0.004826 0)
			(unlocked yes)
			(layer "F.SilkS")
			(effects
				(font
					(size 0.7874 0.5842)
					(thickness 0.1524)
				)
				(justify left)
			)
		)
		(property "Value" ""
			(at 0 0 0)
			(layer "F.Fab")
			(effects
				(font
					(size 1.27 1.27)
				)
			)
		)
		(duplicate_pad_numbers_are_jumpers no)
		(fp_line
			(start -0.7874 -0.4064)
			(end 0.7874 -0.4064)
			(stroke
				(width 0.1524)
				(type default)
			)
			(layer "F.SilkS")
		)
		(fp_line
			(start -0.7874 0.4064)
			(end -0.7874 -0.4064)
			(stroke
				(width 0.1524)
				(type default)
			)
			(layer "F.SilkS")
		)
		(fp_line
			(start 0.7874 -0.4064)
			(end 0.7874 0.4064)
			(stroke
				(width 0.1524)
				(type default)
			)
			(layer "F.SilkS")
		)
		(fp_line
			(start 0.7874 0.4064)
			(end -0.7874 0.4064)
			(stroke
				(width 0.1524)
				(type default)
			)
			(layer "F.SilkS")
		)
		(fp_poly
			(pts
				(xy -0.508 0.2794) (xy -0.508 0.2286) (xy -0.635 0.2286) (xy -0.635 -0.254) (xy -0.5334 -0.254)
				(xy -0.5334 -0.2794) (xy 0.5334 -0.2794) (xy 0.5334 -0.254) (xy 0.635 -0.254) (xy 0.635 0.254) (xy 0.5334 0.254)
				(xy 0.5334 0.2794)
			)
			(stroke
				(width 0)
				(type default)
			)
			(fill no)
			(layer "F.CrtYd")
		)
		(pad "1" smd rect
			(at 0.40005 0)
			(size 0.4572 0.508)
			(layers "F.Cu" "F.Mask" "F.Paste")
			(net "PSU1_CSAHRE")
		)
		(pad "2" smd rect
			(at -0.40005 0)
			(size 0.4572 0.508)
			(layers "F.Cu" "F.Mask" "F.Paste")
			(net "PSU_CSAHRE")
		)
	)
)
